(kicad_pcb
	(version 20260206)
	(generator "pcbnew")
	(generator_version "10.0")
	(general
		(thickness 1.6)
		(legacy_teardrops no)
	)
	(paper "A4")
	(title_block
		(title "01162023_DA0F0TEBIF0_F0T_Expander_BD_F_brd_V02_OCP.brd")
		(comment 1 "Grand Teton / footprints 3222-3225 of 9728")
	)
	(layers
		(0 "F.Cu" signal "TOP")
		(4 "In1.Cu" signal "GND")
		(6 "In2.Cu" signal "VCC")
		(8 "In3.Cu" signal "VCC1")
		(10 "In4.Cu" signal "GND1")
		(12 "In5.Cu" signal "IN1")
		(14 "In6.Cu" signal "GND2")
		(16 "In7.Cu" signal "IN2")
		(18 "In8.Cu" signal "GND3")
		(20 "In9.Cu" signal "IN3")
		(22 "In10.Cu" signal "GND4")
		(24 "In11.Cu" signal "IN4")
		(26 "In12.Cu" signal "GND5")
		(28 "In13.Cu" signal "IN5")
		(30 "In14.Cu" signal "GND6")
		(32 "In15.Cu" signal "IN6")
		(34 "In16.Cu" signal "GND7")
		(2 "B.Cu" signal "BOTTOM")
		(9 "F.Adhes" user "F.Adhesive")
		(11 "B.Adhes" user "B.Adhesive")
		(13 "F.Paste" user "Package Geometry/Pastemask Top")
		(15 "B.Paste" user "Package Geometry/Pastemask Bottom")
		(5 "F.SilkS" user "Ref Des/Silkscreen Top")
		(7 "B.SilkS" user "Ref Des/Silkscreen Bottom")
		(1 "F.Mask" user "Board Geometry/Soldermask Top")
		(3 "B.Mask" user "Board Geometry/Soldermask Bottom")
		(17 "Dwgs.User" user "User.Drawings")
		(19 "Cmts.User" user "User.Comments")
		(21 "Eco1.User" user "User.Eco1")
		(23 "Eco2.User" user "User.Eco2")
		(25 "Edge.Cuts" user "Board Geometry/Outline")
		(27 "Margin" user)
		(31 "F.CrtYd" user "Package Geometry/Place Bound Top")
		(29 "B.CrtYd" user "Package Geometry/Place Bound Bottom")
		(35 "F.Fab" user "Ref Des/Assembly Top")
		(33 "B.Fab" user "Ref Des/Assembly Bottom")
	)
	(footprint ""
		(layer "F.Cu")
		(at 321.84975 -320.900044)
		(property "Reference" "H90"
			(at -6.735826 -7.279386 0)
			(unlocked yes)
			(layer "F.SilkS")
			(effects
				(font
					(size 0.7874 0.5842)
					(thickness 0.1524)
				)
				(justify left)
			)
		)
		(property "Value" ""
			(at 0 0 0)
			(layer "F.Fab")
			(effects
				(font
					(size 1.27 1.27)
				)
			)
		)
		(duplicate_pad_numbers_are_jumpers no)
		(fp_arc
			(start -7.98576 0.476504)
			(mid -0.238348 -7.996428)
			(end 7.999984 0)
			(stroke
				(width 0.1524)
				(type default)
			)
			(layer "F.SilkS")
		)
		(fp_arc
			(start 7.999984 0)
			(mid 3.094955 7.376969)
			(end -5.605272 5.707888)
			(stroke
				(width 0.1524)
				(type default)
			)
			(layer "F.SilkS")
		)
		(fp_arc
			(start -7.996428 0.240284)
			(mid -0.120206 -7.99904)
			(end 7.999984 0)
			(stroke
				(width 0.1524)
				(type default)
			)
			(layer "B.SilkS")
		)
		(fp_arc
			(start 7.999984 0)
			(mid 3.188675 7.336913)
			(end -5.457952 5.848858)
			(stroke
				(width 0.1524)
				(type default)
			)
			(layer "B.SilkS")
		)
		(fp_circle
			(center 0 0)
			(end 7.999984 0)
			(stroke
				(width 0.1)
				(type default)
			)
			(fill no)
			(layer "B.Fab")
		)
		(fp_circle
			(center 0 0)
			(end 7.999984 0)
			(stroke
				(width 0.1)
				(type default)
			)
			(fill no)
			(layer "F.Fab")
		)
		(pad "" np_thru_hole circle
			(at 0 0)
			(size 4.5212 4.5212)
			(drill 4.5212)
			(layers "*.Cu" "*.Mask")
			(clearance 0.381)
			(thermal_gap 0.381)
		)
		(pad "2" thru_hole circle
			(at 3.6322 0)
			(size 0.762 0.762)
			(drill 0.5588)
			(layers "*.Cu" "*.Mask")
			(remove_unused_layers no)
			(net "GND")
			(clearance 0.1524)
			(thermal_gap 0.1524)
		)
		(pad "3" thru_hole circle
			(at 2.568448 -2.568448)
			(size 0.762 0.762)
			(drill 0.5588)
			(layers "*.Cu" "*.Mask")
			(remove_unused_layers no)
			(net "GND")
			(clearance 0.1524)
			(thermal_gap 0.1524)
		)
		(pad "4" thru_hole circle
			(at 0 -3.6322)
			(size 0.762 0.762)
			(drill 0.5588)
			(layers "*.Cu" "*.Mask")
			(remove_unused_layers no)
			(net "GND")
			(clearance 0.1524)
			(thermal_gap 0.1524)
		)
		(pad "5" thru_hole circle
			(at -2.568448 -2.568448)
			(size 0.762 0.762)
			(drill 0.5588)
			(layers "*.Cu" "*.Mask")
			(remove_unused_layers no)
			(net "GND")
			(clearance 0.1524)
			(thermal_gap 0.1524)
		)
		(pad "6" thru_hole circle
			(at -3.6322 0)
			(size 0.762 0.762)
			(drill 0.5588)
			(layers "*.Cu" "*.Mask")
			(remove_unused_layers no)
			(net "GND")
			(clearance 0.1524)
			(thermal_gap 0.1524)
		)
		(pad "7" thru_hole circle
			(at -2.568448 2.568448)
			(size 0.762 0.762)
			(drill 0.5588)
			(layers "*.Cu" "*.Mask")
			(remove_unused_layers no)
			(net "GND")
			(clearance 0.1524)
			(thermal_gap 0.1524)
		)
		(pad "8" thru_hole circle
			(at 0 3.6322)
			(size 0.762 0.762)
			(drill 0.5588)
			(layers "*.Cu" "*.Mask")
			(remove_unused_layers no)
			(net "GND")
			(clearance 0.1524)
			(thermal_gap 0.1524)
		)
		(pad "9" thru_hole circle
			(at 2.568448 2.568448)
			(size 0.762 0.762)
			(drill 0.5588)
			(layers "*.Cu" "*.Mask")
			(remove_unused_layers no)
			(net "GND")
			(clearance 0.1524)
			(thermal_gap 0.1524)
		)
		(zone
			(layer "F.Cu")
			(hatch none 0.5)
			(connect_pads
				(clearance 0)
			)
			(min_thickness 0.25)
			(keepout
				(tracks not_allowed)
				(vias allowed)
				(pads allowed)
				(copperpour not_allowed)
				(footprints allowed)
			)
			(placement
				(enabled no)
				(sheetname "")
			)
			(fill
				(thermal_gap 0.5)
				(thermal_bridge_width 0.5)
				(island_removal_mode 0)
			)
			(polygon
				(pts
					(arc
						(start 321.84975 -312.90006)
						(mid 313.849766 -320.900044)
						(end 321.84975 -328.900028)
					)
					(arc
						(start 321.84975 -325.649844)
						(mid 317.09995 -320.900044)
						(end 321.84975 -316.150244)
					)
				)
			)
		)
		(zone
			(layer "F.Cu")
			(hatch none 0.5)
			(connect_pads
				(clearance 0)
			)
			(min_thickness 0.25)
			(keepout
				(tracks not_allowed)
				(vias allowed)
				(pads allowed)
				(copperpour not_allowed)
				(footprints allowed)
			)
			(placement
				(enabled no)
				(sheetname "")
			)
			(fill
				(thermal_gap 0.5)
				(thermal_bridge_width 0.5)
				(island_removal_mode 0)
			)
			(polygon
				(pts
					(arc
						(start 321.84975 -312.90006)
						(mid 329.849734 -320.900044)
						(end 321.84975 -328.900028)
					)
					(arc
						(start 321.84975 -325.649844)
						(mid 326.59955 -320.900044)
						(end 321.84975 -316.150244)
					)
				)
			)
		)
		(zone
			(layers "F.Cu" "B.Cu" "In1.Cu" "In2.Cu" "In3.Cu" "In4.Cu" "In5.Cu" "In6.Cu"
				"In7.Cu" "In8.Cu" "In9.Cu" "In10.Cu" "In11.Cu" "In12.Cu" "In13.Cu" "In14.Cu"
				"In15.Cu" "In16.Cu"
			)
			(hatch none 0.5)
			(connect_pads
				(clearance 0)
			)
			(min_thickness 0.25)
			(keepout
				(tracks not_allowed)
				(vias allowed)
				(pads allowed)
				(copperpour not_allowed)
				(footprints allowed)
			)
			(placement
				(enabled no)
				(sheetname "")
			)
			(fill
				(thermal_gap 0.5)
				(thermal_bridge_width 0.5)
				(island_removal_mode 0)
			)
			(polygon
				(pts
					(arc
						(start 324.61581 -320.900044)
						(mid 319.08369 -320.900044)
						(end 324.61581 -320.900044)
					)
				)
			)
		)
		(zone
			(layer "B.Cu")
			(hatch none 0.5)
			(connect_pads
				(clearance 0)
			)
			(min_thickness 0.25)
			(keepout
				(tracks not_allowed)
				(vias allowed)
				(pads allowed)
				(copperpour not_allowed)
				(footprints allowed)
			)
			(placement
				(enabled no)
				(sheetname "")
			)
			(fill
				(thermal_gap 0.5)
				(thermal_bridge_width 0.5)
				(island_removal_mode 0)
			)
			(polygon
				(pts
					(arc
						(start 321.84975 -315.896244)
						(mid 316.84595 -320.900044)
						(end 321.84975 -325.903844)
					)
					(arc
						(start 321.84975 -325.421244)
						(mid 317.32855 -320.900044)
						(end 321.84975 -316.378844)
					)
				)
			)
		)
		(zone
			(layer "B.Cu")
			(hatch none 0.5)
			(connect_pads
				(clearance 0)
			)
			(min_thickness 0.25)
			(keepout
				(tracks not_allowed)
				(vias allowed)
				(pads allowed)
				(copperpour not_allowed)
				(footprints allowed)
			)
			(placement
				(enabled no)
				(sheetname "")
			)
			(fill
				(thermal_gap 0.5)
				(thermal_bridge_width 0.5)
				(island_removal_mode 0)
			)
			(polygon
				(pts
					(arc
						(start 321.84975 -315.896244)
						(mid 326.85355 -320.900044)
						(end 321.84975 -325.903844)
					)
					(arc
						(start 321.84975 -325.421244)
						(mid 326.37095 -320.900044)
						(end 321.84975 -316.378844)
					)
				)
			)
		)
	)
	(footprint ""
		(layer "F.Cu")
		(at 361.89031 -254.194564 180)
		(property "Reference" "R833"
			(at 0 0 180)
			(layer "F.SilkS")
			(hide yes)
			(effects
				(font
					(size 1.27 1.27)
				)
			)
		)
		(property "Value" ""
			(at 0 0 180)
			(layer "F.Fab")
			(effects
				(font
					(size 1.27 1.27)
				)
			)
		)
		(duplicate_pad_numbers_are_jumpers no)
		(fp_line
			(start 0.7874 0.4064)
			(end -0.7874 0.4064)
			(stroke
				(width 0.1524)
				(type default)
			)
			(layer "F.SilkS")
		)
		(fp_line
			(start 0.7874 -0.4064)
			(end 0.7874 0.4064)
			(stroke
				(width 0.1524)
				(type default)
			)
			(layer "F.SilkS")
		)
		(fp_line
			(start -0.7874 0.4064)
			(end -0.7874 -0.4064)
			(stroke
				(width 0.1524)
				(type default)
			)
			(layer "F.SilkS")
		)
		(fp_line
			(start -0.7874 -0.4064)
			(end 0.7874 -0.4064)
			(stroke
				(width 0.1524)
				(type default)
			)
			(layer "F.SilkS")
		)
		(fp_line
			(start 0.67945 0.3048)
			(end 0.120396 0.3048)
			(stroke
				(width 0.1)
				(type default)
			)
			(layer "F.Fab")
		)
		(fp_line
			(start 0.67945 -0.3048)
			(end 0.67945 0.3048)
			(stroke
				(width 0.1)
				(type default)
			)
			(layer "F.Fab")
		)
		(fp_line
			(start 0.12065 -0.2794)
			(end 0.12065 -0.3048)
			(stroke
				(width 0.1)
				(type default)
			)
			(layer "F.Fab")
		)
		(fp_line
			(start 0.12065 -0.3048)
			(end 0.67945 -0.3048)
			(stroke
				(width 0.1)
				(type default)
			)
			(layer "F.Fab")
		)
		(fp_line
			(start 0.120396 0.3048)
			(end 0.120396 0.2794)
			(stroke
				(width 0.1)
				(type default)
			)
			(layer "F.Fab")
		)
		(fp_line
			(start 0.120396 0.2794)
			(end -0.12065 0.2794)
			(stroke
				(width 0.1)
				(type default)
			)
			(layer "F.Fab")
		)
		(fp_line
			(start -0.12065 0.3048)
			(end -0.67945 0.3048)
			(stroke
				(width 0.1)
				(type default)
			)
			(layer "F.Fab")
		)
		(fp_line
			(start -0.12065 0.2794)
			(end -0.12065 0.3048)
			(stroke
				(width 0.1)
				(type default)
			)
			(layer "F.Fab")
		)
		(fp_line
			(start -0.12065 -0.2794)
			(end 0.12065 -0.2794)
			(stroke
				(width 0.1)
				(type default)
			)
			(layer "F.Fab")
		)
		(fp_line
			(start -0.12065 -0.305054)
			(end -0.12065 -0.2794)
			(stroke
				(width 0.1)
				(type default)
			)
			(layer "F.Fab")
		)
		(fp_line
			(start -0.67945 0.3048)
			(end -0.67945 -0.305054)
			(stroke
				(width 0.1)
				(type default)
			)
			(layer "F.Fab")
		)
		(fp_line
			(start -0.67945 -0.305054)
			(end -0.12065 -0.305054)
			(stroke
				(width 0.1)
				(type default)
			)
			(layer "F.Fab")
		)
		(pad "1" smd circle
			(at -0.40005 0 180)
			(size 0 0)
			(layers "F.Cu" "F.Mask" "F.Paste")
			(net "P3V3_AUX")
		)
		(pad "2" smd circle
			(at 0.40005 0 180)
			(size 0 0)
			(layers "F.Cu" "F.Mask" "F.Paste")
			(net "P0V8_PEX2_AVRRDY")
		)
	)
	(footprint ""
		(layer "F.Cu")
		(at 78.243684 -49.95291 180)
		(property "Reference" "R533"
			(at 0 0 180)
			(layer "F.SilkS")
			(hide yes)
			(effects
				(font
					(size 1.27 1.27)
				)
			)
		)
		(property "Value" ""
			(at 0 0 180)
			(layer "F.Fab")
			(effects
				(font
					(size 1.27 1.27)
				)
			)
		)
		(duplicate_pad_numbers_are_jumpers no)
		(fp_line
			(start 0.7874 0.4064)
			(end -0.7874 0.4064)
			(stroke
				(width 0.1524)
				(type default)
			)
			(layer "F.SilkS")
		)
		(fp_line
			(start 0.7874 -0.4064)
			(end 0.7874 0.4064)
			(stroke
				(width 0.1524)
				(type default)
			)
			(layer "F.SilkS")
		)
		(fp_line
			(start -0.7874 0.4064)
			(end -0.7874 -0.4064)
			(stroke
				(width 0.1524)
				(type default)
			)
			(layer "F.SilkS")
		)
		(fp_line
			(start -0.7874 -0.4064)
			(end 0.7874 -0.4064)
			(stroke
				(width 0.1524)
				(type default)
			)
			(layer "F.SilkS")
		)
		(fp_line
			(start 0.67945 0.3048)
			(end 0.120396 0.3048)
			(stroke
				(width 0.1)
				(type default)
			)
			(layer "F.Fab")
		)
		(fp_line
			(start 0.67945 -0.3048)
			(end 0.67945 0.3048)
			(stroke
				(width 0.1)
				(type default)
			)
			(layer "F.Fab")
		)
		(fp_line
			(start 0.12065 -0.2794)
			(end 0.12065 -0.3048)
			(stroke
				(width 0.1)
				(type default)
			)
			(layer "F.Fab")
		)
		(fp_line
			(start 0.12065 -0.3048)
			(end 0.67945 -0.3048)
			(stroke
				(width 0.1)
				(type default)
			)
			(layer "F.Fab")
		)
		(fp_line
			(start 0.120396 0.3048)
			(end 0.120396 0.2794)
			(stroke
				(width 0.1)
				(type default)
			)
			(layer "F.Fab")
		)
		(fp_line
			(start 0.120396 0.2794)
			(end -0.12065 0.2794)
			(stroke
				(width 0.1)
				(type default)
			)
			(layer "F.Fab")
		)
		(fp_line
			(start -0.12065 0.3048)
			(end -0.67945 0.3048)
			(stroke
				(width 0.1)
				(type default)
			)
			(layer "F.Fab")
		)
		(fp_line
			(start -0.12065 0.2794)
			(end -0.12065 0.3048)
			(stroke
				(width 0.1)
				(type default)
			)
			(layer "F.Fab")
		)
		(fp_line
			(start -0.12065 -0.2794)
			(end 0.12065 -0.2794)
			(stroke
				(width 0.1)
				(type default)
			)
			(layer "F.Fab")
		)
		(fp_line
			(start -0.12065 -0.305054)
			(end -0.12065 -0.2794)
			(stroke
				(width 0.1)
				(type default)
			)
			(layer "F.Fab")
		)
		(fp_line
			(start -0.67945 0.3048)
			(end -0.67945 -0.305054)
			(stroke
				(width 0.1)
				(type default)
			)
			(layer "F.Fab")
		)
		(fp_line
			(start -0.67945 -0.305054)
			(end -0.12065 -0.305054)
			(stroke
				(width 0.1)
				(type default)
			)
			(layer "F.Fab")
		)
		(pad "1" smd circle
			(at -0.40005 0 180)
			(size 0 0)
			(layers "F.Cu" "F.Mask" "F.Paste")
			(net "SMB_BIC_I2C6_MUX_SSD_0_7_ADC_R_SCL")
		)
		(pad "2" smd circle
			(at 0.40005 0 180)
			(size 0 0)
			(layers "F.Cu" "F.Mask" "F.Paste")
			(net "SMB_SSD2_ADC_SCL")
		)
	)
	(footprint ""
		(layer "F.Cu")
		(at 334.130396 -119.77624)
		(property "Reference" "R6033"
			(at 0 0 0)
			(layer "F.SilkS")
			(hide yes)
			(effects
				(font
					(size 1.27 1.27)
				)
			)
		)
		(property "Value" ""
			(at 0 0 0)
			(layer "F.Fab")
			(effects
				(font
					(size 1.27 1.27)
				)
			)
		)
		(duplicate_pad_numbers_are_jumpers no)
		(fp_line
			(start -0.7874 -0.4064)
			(end 0.7874 -0.4064)
			(stroke
				(width 0.1524)
				(type default)
			)
			(layer "F.SilkS")
		)
		(fp_line
			(start -0.7874 0.4064)
			(end -0.7874 -0.4064)
			(stroke
				(width 0.1524)
				(type default)
			)
			(layer "F.SilkS")
		)
		(fp_line
			(start 0.7874 -0.4064)
			(end 0.7874 0.4064)
			(stroke
				(width 0.1524)
				(type default)
			)
			(layer "F.SilkS")
		)
		(fp_line
			(start 0.7874 0.4064)
			(end -0.7874 0.4064)
			(stroke
				(width 0.1524)
				(type default)
			)
			(layer "F.SilkS")
		)
		(fp_line
			(start -0.67945 -0.305054)
			(end -0.12065 -0.305054)
			(stroke
				(width 0.1)
				(type default)
			)
			(layer "F.Fab")
		)
		(fp_line
			(start -0.67945 0.3048)
			(end -0.67945 -0.305054)
			(stroke
				(width 0.1)
				(type default)
			)
			(layer "F.Fab")
		)
		(fp_line
			(start -0.12065 -0.305054)
			(end -0.12065 -0.2794)
			(stroke
				(width 0.1)
				(type default)
			)
			(layer "F.Fab")
		)
		(fp_line
			(start -0.12065 -0.2794)
			(end 0.12065 -0.2794)
			(stroke
				(width 0.1)
				(type default)
			)
			(layer "F.Fab")
		)
		(fp_line
			(start -0.12065 0.2794)
			(end -0.12065 0.3048)
			(stroke
				(width 0.1)
				(type default)
			)
			(layer "F.Fab")
		)
		(fp_line
			(start -0.12065 0.3048)
			(end -0.67945 0.3048)
			(stroke
				(width 0.1)
				(type default)
			)
			(layer "F.Fab")
		)
		(fp_line
			(start 0.120396 0.2794)
			(end -0.12065 0.2794)
			(stroke
				(width 0.1)
				(type default)
			)
			(layer "F.Fab")
		)
		(fp_line
			(start 0.120396 0.3048)
			(end 0.120396 0.2794)
			(stroke
				(width 0.1)
				(type default)
			)
			(layer "F.Fab")
		)
		(fp_line
			(start 0.12065 -0.3048)
			(end 0.67945 -0.3048)
			(stroke
				(width 0.1)
				(type default)
			)
			(layer "F.Fab")
		)
		(fp_line
			(start 0.12065 -0.2794)
			(end 0.12065 -0.3048)
			(stroke
				(width 0.1)
				(type default)
			)
			(layer "F.Fab")
		)
		(fp_line
			(start 0.67945 -0.3048)
			(end 0.67945 0.3048)
			(stroke
				(width 0.1)
				(type default)
			)
			(layer "F.Fab")
		)
		(fp_line
			(start 0.67945 0.3048)
			(end 0.120396 0.3048)
			(stroke
				(width 0.1)
				(type default)
			)
			(layer "F.Fab")
		)
		(pad "1" smd circle
			(at -0.40005 0)
			(size 0 0)
			(layers "F.Cu" "F.Mask" "F.Paste")
			(net "P3V3_AUX")
		)
		(pad "2" smd circle
			(at 0.40005 0)
			(size 0 0)
			(layers "F.Cu" "F.Mask" "F.Paste")
			(net "PWRGD_P3V3_NIC5_D")
		)
	)
)
